(kicad_pcb
	(version 20241229)
	(generator "pcbnew")
	(generator_version "9.0")
	(general
		(thickness 1.59)
		(legacy_teardrops no)
	)
	(paper "A3")
	(title_block
		(title "usb-c-power-adapter")
		(date "2025-06-24")
		(rev "1.1.2")
		(company "Antmicro")
		(comment 9 "footprints 104-108 of 122")
	)
	(layers
		(0 "F.Cu" signal)
		(4 "In1.Cu" signal)
		(6 "In2.Cu" signal)
		(2 "B.Cu" signal)
		(9 "F.Adhes" user "F.Adhesive")
		(11 "B.Adhes" user "B.Adhesive")
		(13 "F.Paste" user)
		(15 "B.Paste" user)
		(5 "F.SilkS" user "F.Silkscreen")
		(7 "B.SilkS" user "B.Silkscreen")
		(1 "F.Mask" user)
		(3 "B.Mask" user)
		(17 "Dwgs.User" user "User.Drawings")
		(19 "Cmts.User" user "User.Comments")
		(21 "Eco1.User" user "User.Eco1")
		(23 "Eco2.User" user "User.Eco2")
		(25 "Edge.Cuts" user)
		(27 "Margin" user)
		(31 "F.CrtYd" user "F.Courtyard")
		(29 "B.CrtYd" user "B.Courtyard")
		(35 "F.Fab" user)
		(33 "B.Fab" user)
	)
	(footprint "antmicro-footprints:C_0805_2012Metric"
		(layer "B.Cu")
		(at 88.95 93.05 -90)
		(descr "Capacitor SMD 0805")
		(tags "capacitor SMD 0805")
		(property "Reference" "C17"
			(at -17.231 4.874 180)
			(layer "B.SilkS")
			(effects
				(font
					(size 0.7 0.7)
					(thickness 0.15)
				)
				(justify left bottom mirror)
			)
		)
		(property "Value" "C_22u_25V_0805"
			(at -2.055717 -1.963152 90)
			(layer "B.Fab")
			(effects
				(font
					(size 0.7 0.7)
					(thickness 0.15)
				)
				(justify left bottom mirror)
			)
		)
		(property "Datasheet" "https://product.samsungsem.com/mlcc/CL21A226MAYNNN.do"
			(at 0 0 270)
			(layer "F.Fab")
			(hide yes)
			(effects
				(font
					(size 1.27 1.27)
					(thickness 0.15)
				)
			)
		)
		(property "Description" "SMT Multilayer Ceramic Capacitor, 22uF, +/-20%, 25V, X5R, 0805 [2012 Metric]"
			(at 0 0 270)
			(layer "F.Fab")
			(hide yes)
			(effects
				(font
					(size 1.27 1.27)
					(thickness 0.15)
				)
			)
		)
		(property "MPN" "CL21A226MAYNNNE"
			(at 0 0 270)
			(unlocked yes)
			(layer "B.Fab")
			(hide yes)
			(effects
				(font
					(size 1 1)
					(thickness 0.15)
				)
				(justify mirror)
			)
		)
		(property "Manufacturer" "Samsung Electro-Mechanics"
			(at 0 0 270)
			(unlocked yes)
			(layer "B.Fab")
			(hide yes)
			(effects
				(font
					(size 1 1)
					(thickness 0.15)
				)
				(justify mirror)
			)
		)
		(property "License" "Apache-2.0"
			(at 0 0 270)
			(unlocked yes)
			(layer "B.Fab")
			(hide yes)
			(effects
				(font
					(size 1 1)
					(thickness 0.15)
				)
				(justify mirror)
			)
		)
		(property "Author" "Antmicro"
			(at 0 0 270)
			(unlocked yes)
			(layer "B.Fab")
			(hide yes)
			(effects
				(font
					(size 1 1)
					(thickness 0.15)
				)
				(justify mirror)
			)
		)
		(property "Val" "22u"
			(at 0 0 270)
			(unlocked yes)
			(layer "B.Fab")
			(hide yes)
			(effects
				(font
					(size 1 1)
					(thickness 0.15)
				)
				(justify mirror)
			)
		)
		(property "Voltage" "25V"
			(at 0 0 270)
			(unlocked yes)
			(layer "B.Fab")
			(hide yes)
			(effects
				(font
					(size 1 1)
					(thickness 0.15)
				)
				(justify mirror)
			)
		)
		(property "Dielectric" "X5R"
			(at 0 0 270)
			(unlocked yes)
			(layer "B.Fab")
			(hide yes)
			(effects
				(font
					(size 1 1)
					(thickness 0.15)
				)
				(justify mirror)
			)
		)
		(property "Public" "False"
			(at 0 0 270)
			(unlocked yes)
			(layer "B.Fab")
			(hide yes)
			(effects
				(font
					(size 1 1)
					(thickness 0.15)
				)
				(justify mirror)
			)
		)
		(sheetname "/DC-DC Converters/")
		(sheetfile "dc-dc_converters.kicad_sch")
		(attr smd)
		(fp_line
			(start 0.3 0.7)
			(end -0.3 0.7)
			(stroke
				(width 0.15)
				(type solid)
			)
			(layer "B.SilkS")
		)
		(fp_line
			(start 0.3 -0.7)
			(end -0.3 -0.7)
			(stroke
				(width 0.15)
				(type solid)
			)
			(layer "B.SilkS")
		)
		(fp_rect
			(start 1.95 0.9)
			(end -1.95 -0.9)
			(stroke
				(width 0.05)
				(type default)
			)
			(fill no)
			(layer "B.CrtYd")
		)
		(fp_rect
			(start -0.95 0.675)
			(end 0.95 -0.675)
			(stroke
				(width 0.15)
				(type solid)
			)
			(fill no)
			(layer "B.Fab")
		)
		(pad "1" smd roundrect
			(at -1.1 0 270)
			(size 1.2 1.3)
			(layers "B.Cu" "B.Mask" "B.Paste")
			(roundrect_rratio 0.25)
			(net 2 "GND")
			(pintype "passive")
		)
		(pad "2" smd roundrect
			(at 1.1 0 270)
			(size 1.2 1.3)
			(layers "B.Cu" "B.Mask" "B.Paste")
			(roundrect_rratio 0.25)
			(net 5 "+12V")
			(pintype "passive")
		)
	)
	(footprint "antmicro-footprints:WSON-6-1EP_2x2mm_P0.65mm"
		(layer "B.Cu")
		(at 86.9 66.9)
		(property "Reference" "U8"
			(at -1.175 2.188 0)
			(layer "B.SilkS")
			(effects
				(font
					(size 0.7 0.7)
					(thickness 0.15)
				)
				(justify right bottom mirror)
			)
		)
		(property "Value" "TVS2200DRVR"
			(at 0 -2.2 0)
			(layer "B.Fab")
			(effects
				(font
					(size 0.7 0.7)
					(thickness 0.15)
				)
				(justify right bottom mirror)
			)
		)
		(property "Datasheet" "https://www.ti.com/lit/ds/symlink/tvs2200.pdf?ts=1712230685180&ref_url=https%253A%252F%252Fwww.ti.com%252Fproduct%252FTVS2200"
			(at 0 0 0)
			(layer "F.Fab")
			(hide yes)
			(effects
				(font
					(size 1.27 1.27)
					(thickness 0.15)
				)
			)
		)
		(property "Description" "ESD Protection Device, 1 kV, WSON-6, 22 V, 105 pF"
			(at 0 0 0)
			(layer "F.Fab")
			(hide yes)
			(effects
				(font
					(size 1.27 1.27)
					(thickness 0.15)
				)
			)
		)
		(property "MPN" "TVS2200DRVR"
			(at 0 0 0)
			(unlocked yes)
			(layer "B.Fab")
			(hide yes)
			(effects
				(font
					(size 1 1)
					(thickness 0.15)
				)
				(justify mirror)
			)
		)
		(property "Manufacturer" "Texas Instruments"
			(at 0 0 0)
			(unlocked yes)
			(layer "B.Fab")
			(hide yes)
			(effects
				(font
					(size 1 1)
					(thickness 0.15)
				)
				(justify mirror)
			)
		)
		(property "License" "Apache-2.0"
			(at 0 0 0)
			(unlocked yes)
			(layer "B.Fab")
			(hide yes)
			(effects
				(font
					(size 1 1)
					(thickness 0.15)
				)
				(justify mirror)
			)
		)
		(property "Author" "Antmicro"
			(at 0 0 0)
			(unlocked yes)
			(layer "B.Fab")
			(hide yes)
			(effects
				(font
					(size 1 1)
					(thickness 0.15)
				)
				(justify mirror)
			)
		)
		(sheetname "/USB PD/")
		(sheetfile "usb_pd.kicad_sch")
		(attr smd)
		(fp_line
			(start -1.05 1)
			(end 1 1)
			(stroke
				(width 0.12)
				(type solid)
			)
			(layer "B.SilkS")
		)
		(fp_line
			(start 1 -1)
			(end -1 -1)
			(stroke
				(width 0.12)
				(type solid)
			)
			(layer "B.SilkS")
		)
		(fp_circle
			(center -1.275 1.075)
			(end -1.224 1.075)
			(stroke
				(width 0.15)
				(type solid)
			)
			(fill yes)
			(layer "B.SilkS")
		)
		(fp_rect
			(start -1.45 1.25)
			(end 1.45 -1.25)
			(stroke
				(width 0.05)
				(type solid)
			)
			(fill no)
			(layer "B.CrtYd")
		)
		(pad "1" smd roundrect
			(at -0.975 0.652)
			(size 0.45 0.4)
			(layers "B.Cu" "B.Mask" "B.Paste")
			(roundrect_rratio 0.25)
			(net 2 "GND")
			(pinfunction "GND")
			(pintype "passive")
		)
		(pad "2" smd roundrect
			(at -0.975 0)
			(size 0.45 0.4)
			(layers "B.Cu" "B.Mask" "B.Paste")
			(roundrect_rratio 0.25)
			(net 2 "GND")
			(pinfunction "GND")
			(pintype "passive")
		)
		(pad "3" smd roundrect
			(at -0.975 -0.65)
			(size 0.45 0.4)
			(layers "B.Cu" "B.Mask" "B.Paste")
			(roundrect_rratio 0.25)
			(net 2 "GND")
			(pinfunction "GND")
			(pintype "passive")
		)
		(pad "4" smd roundrect
			(at 0.973 -0.65)
			(size 0.45 0.4)
			(layers "B.Cu" "B.Mask" "B.Paste")
			(roundrect_rratio 0.25)
			(net 33 "/USB PD/CC2")
			(pinfunction "IN")
			(pintype "passive")
		)
		(pad "5" smd roundrect
			(at 0.973 0)
			(size 0.45 0.4)
			(layers "B.Cu" "B.Mask" "B.Paste")
			(roundrect_rratio 0.25)
			(net 33 "/USB PD/CC2")
			(pinfunction "IN")
			(pintype "passive")
		)
		(pad "6" smd roundrect
			(at 0.973 0.652)
			(size 0.45 0.4)
			(layers "B.Cu" "B.Mask" "B.Paste")
			(roundrect_rratio 0.25)
			(net 33 "/USB PD/CC2")
			(pinfunction "IN")
			(pintype "passive")
		)
		(pad "7" smd roundrect
			(at 0 0)
			(size 1.12 1.72)
			(layers "B.Cu" "B.Mask" "B.Paste")
			(roundrect_rratio 0.1)
			(net 2 "GND")
			(pinfunction "GND")
			(pintype "passive")
		)
	)
	(footprint "antmicro-footprints:SOD-123FL"
		(layer "B.Cu")
		(at 83.5 95.7 90)
		(property "Reference" "D5"
			(at -3.65 0.576 0)
			(layer "B.SilkS")
			(effects
				(font
					(size 0.7 0.7)
					(thickness 0.15)
				)
				(justify left bottom mirror)
			)
		)
		(property "Value" "SZSMF4L12AT3G"
			(at 0 -1.967 90)
			(layer "B.Fab")
			(effects
				(font
					(size 0.7 0.7)
					(thickness 0.15)
				)
				(justify right bottom mirror)
			)
		)
		(property "Datasheet" "https://www.mouser.com/datasheet/2/240/media-3320461.pdf"
			(at 0 0 90)
			(layer "F.Fab")
			(hide yes)
			(effects
				(font
					(size 1.27 1.27)
					(thickness 0.15)
				)
			)
		)
		(property "Description" "ESD, TVS Diode, 14V, UNI, 400W, SOD-123FL"
			(at 0 0 90)
			(layer "F.Fab")
			(hide yes)
			(effects
				(font
					(size 1.27 1.27)
					(thickness 0.15)
				)
			)
		)
		(property "MPN" "SZSMF4L12AT3G"
			(at 0 0 90)
			(unlocked yes)
			(layer "B.Fab")
			(hide yes)
			(effects
				(font
					(size 1 1)
					(thickness 0.15)
				)
				(justify mirror)
			)
		)
		(property "Author" "Antmicro"
			(at 0 0 90)
			(unlocked yes)
			(layer "B.Fab")
			(hide yes)
			(effects
				(font
					(size 1 1)
					(thickness 0.15)
				)
				(justify mirror)
			)
		)
		(property "License" "Apache-2.0"
			(at 0 0 90)
			(unlocked yes)
			(layer "B.Fab")
			(hide yes)
			(effects
				(font
					(size 1 1)
					(thickness 0.15)
				)
				(justify mirror)
			)
		)
		(property "Manufacturer" "Littelfuse"
			(at 0 0 90)
			(unlocked yes)
			(layer "B.Fab")
			(hide yes)
			(effects
				(font
					(size 1 1)
					(thickness 0.15)
				)
				(justify mirror)
			)
		)
		(sheetname "/DC-DC Converters/")
		(sheetfile "dc-dc_converters.kicad_sch")
		(attr smd)
		(fp_line
			(start 0 -1.1)
			(end -2.3 -1.1)
			(stroke
				(width 0.15)
				(type solid)
			)
			(layer "B.SilkS")
		)
		(fp_line
			(start -2.3 -1.1)
			(end -2.3 1.1)
			(stroke
				(width 0.15)
				(type solid)
			)
			(layer "B.SilkS")
		)
		(fp_line
			(start -2.3 1.1)
			(end 0 1.1)
			(stroke
				(width 0.15)
				(type solid)
			)
			(layer "B.SilkS")
		)
		(fp_rect
			(start -2.35 1.125)
			(end 2.35 -1.125)
			(stroke
				(width 0.05)
				(type solid)
			)
			(fill no)
			(layer "B.CrtYd")
		)
		(fp_rect
			(start -0.775 0.875)
			(end -0.525 -0.875)
			(stroke
				(width 0.15)
				(type solid)
			)
			(fill yes)
			(layer "B.Fab")
		)
		(fp_rect
			(start -1.825 0.875)
			(end 1.824 -0.873)
			(stroke
				(width 0.15)
				(type solid)
			)
			(fill no)
			(layer "B.Fab")
		)
		(pad "1" smd roundrect
			(at -1.43 0 90)
			(size 1.34 1.8)
			(layers "B.Cu" "B.Mask" "B.Paste")
			(roundrect_rratio 0.14)
			(net 26 "Net-(D5-C)")
			(pinfunction "C")
			(pintype "passive")
		)
		(pad "2" smd roundrect
			(at 1.429 0 90)
			(size 1.34 1.8)
			(layers "B.Cu" "B.Mask" "B.Paste")
			(roundrect_rratio 0.14)
			(net 2 "GND")
			(pinfunction "A")
			(pintype "passive")
		)
	)
	(footprint "antmicro-footprints:C_0805_2012Metric"
		(layer "B.Cu")
		(at 92.55 93.05 -90)
		(descr "Capacitor SMD 0805")
		(tags "capacitor SMD 0805")
		(property "Reference" "C32"
			(at -19.263 8.474 180)
			(layer "B.SilkS")
			(effects
				(font
					(size 0.7 0.7)
					(thickness 0.15)
				)
				(justify left bottom mirror)
			)
		)
		(property "Value" "C_22u_25V_0805"
			(at -2.055717 -1.963152 90)
			(layer "B.Fab")
			(effects
				(font
					(size 0.7 0.7)
					(thickness 0.15)
				)
				(justify left bottom mirror)
			)
		)
		(property "Datasheet" "https://product.samsungsem.com/mlcc/CL21A226MAYNNN.do"
			(at 0 0 270)
			(layer "F.Fab")
			(hide yes)
			(effects
				(font
					(size 1.27 1.27)
					(thickness 0.15)
				)
			)
		)
		(property "Description" "SMT Multilayer Ceramic Capacitor, 22uF, +/-20%, 25V, X5R, 0805 [2012 Metric]"
			(at 0 0 270)
			(layer "F.Fab")
			(hide yes)
			(effects
				(font
					(size 1.27 1.27)
					(thickness 0.15)
				)
			)
		)
		(property "MPN" "CL21A226MAYNNNE"
			(at 0 0 270)
			(unlocked yes)
			(layer "B.Fab")
			(hide yes)
			(effects
				(font
					(size 1 1)
					(thickness 0.15)
				)
				(justify mirror)
			)
		)
		(property "Manufacturer" "Samsung Electro-Mechanics"
			(at 0 0 270)
			(unlocked yes)
			(layer "B.Fab")
			(hide yes)
			(effects
				(font
					(size 1 1)
					(thickness 0.15)
				)
				(justify mirror)
			)
		)
		(property "License" "Apache-2.0"
			(at 0 0 270)
			(unlocked yes)
			(layer "B.Fab")
			(hide yes)
			(effects
				(font
					(size 1 1)
					(thickness 0.15)
				)
				(justify mirror)
			)
		)
		(property "Author" "Antmicro"
			(at 0 0 270)
			(unlocked yes)
			(layer "B.Fab")
			(hide yes)
			(effects
				(font
					(size 1 1)
					(thickness 0.15)
				)
				(justify mirror)
			)
		)
		(property "Val" "22u"
			(at 0 0 270)
			(unlocked yes)
			(layer "B.Fab")
			(hide yes)
			(effects
				(font
					(size 1 1)
					(thickness 0.15)
				)
				(justify mirror)
			)
		)
		(property "Voltage" "25V"
			(at 0 0 270)
			(unlocked yes)
			(layer "B.Fab")
			(hide yes)
			(effects
				(font
					(size 1 1)
					(thickness 0.15)
				)
				(justify mirror)
			)
		)
		(property "Dielectric" "X5R"
			(at 0 0 270)
			(unlocked yes)
			(layer "B.Fab")
			(hide yes)
			(effects
				(font
					(size 1 1)
					(thickness 0.15)
				)
				(justify mirror)
			)
		)
		(property "Public" "False"
			(at 0 0 270)
			(unlocked yes)
			(layer "B.Fab")
			(hide yes)
			(effects
				(font
					(size 1 1)
					(thickness 0.15)
				)
				(justify mirror)
			)
		)
		(sheetname "/DC-DC Converters/")
		(sheetfile "dc-dc_converters.kicad_sch")
		(attr smd)
		(fp_line
			(start 0.3 0.7)
			(end -0.3 0.7)
			(stroke
				(width 0.15)
				(type solid)
			)
			(layer "B.SilkS")
		)
		(fp_line
			(start 0.3 -0.7)
			(end -0.3 -0.7)
			(stroke
				(width 0.15)
				(type solid)
			)
			(layer "B.SilkS")
		)
		(fp_rect
			(start 1.95 0.9)
			(end -1.95 -0.9)
			(stroke
				(width 0.05)
				(type default)
			)
			(fill no)
			(layer "B.CrtYd")
		)
		(fp_rect
			(start -0.95 0.675)
			(end 0.95 -0.675)
			(stroke
				(width 0.15)
				(type solid)
			)
			(fill no)
			(layer "B.Fab")
		)
		(pad "1" smd roundrect
			(at -1.1 0 270)
			(size 1.2 1.3)
			(layers "B.Cu" "B.Mask" "B.Paste")
			(roundrect_rratio 0.25)
			(net 2 "GND")
			(pintype "passive")
		)
		(pad "2" smd roundrect
			(at 1.1 0 270)
			(size 1.2 1.3)
			(layers "B.Cu" "B.Mask" "B.Paste")
			(roundrect_rratio 0.25)
			(net 5 "+12V")
			(pintype "passive")
		)
	)
	(footprint "antmicro-footprints:SOT-563"
		(layer "B.Cu")
		(at 85.8 82.65)
		(property "Reference" "U4"
			(at 2.084 -0.862 0)
			(layer "B.SilkS")
			(effects
				(font
					(size 0.7 0.7)
					(thickness 0.15)
				)
				(justify right bottom mirror)
			)
		)
		(property "Value" "AP62301Z6-7"
			(at 0 -2 0)
			(layer "B.Fab")
			(effects
				(font
					(size 0.7 0.7)
					(thickness 0.15)
				)
				(justify right bottom mirror)
			)
		)
		(property "Datasheet" "https://www.diodes.com/assets/Datasheets/AP62300_AP62301_AP62300T.pdf"
			(at 0 0 0)
			(layer "F.Fab")
			(hide yes)
			(effects
				(font
					(size 1.27 1.27)
					(thickness 0.15)
				)
			)
		)
		(property "Description" "DC-DC Switching Synchronous Buck Regulator, Adjustable, 4.2V-18Vin, 0.8V-7V/3A out, SOT-563-6"
			(at 0 0 0)
			(layer "F.Fab")
			(hide yes)
			(effects
				(font
					(size 1.27 1.27)
					(thickness 0.15)
				)
			)
		)
		(property "MPN" "AP62301Z6-7"
			(at 0 0 0)
			(unlocked yes)
			(layer "B.Fab")
			(hide yes)
			(effects
				(font
					(size 1 1)
					(thickness 0.15)
				)
				(justify mirror)
			)
		)
		(property "Manufacturer" "Diodes Incorporated"
			(at 0 0 0)
			(unlocked yes)
			(layer "B.Fab")
			(hide yes)
			(effects
				(font
					(size 1 1)
					(thickness 0.15)
				)
				(justify mirror)
			)
		)
		(property "Author" "Antmicro"
			(at 0 0 0)
			(unlocked yes)
			(layer "B.Fab")
			(hide yes)
			(effects
				(font
					(size 1 1)
					(thickness 0.15)
				)
				(justify mirror)
			)
		)
		(property "License" "Apache-2.0"
			(at 0 0 0)
			(unlocked yes)
			(layer "B.Fab")
			(hide yes)
			(effects
				(font
					(size 1 1)
					(thickness 0.15)
				)
				(justify mirror)
			)
		)
		(sheetname "/DC-DC Converters/")
		(sheetfile "dc-dc_converters.kicad_sch")
		(attr smd)
		(fp_line
			(start -0.778 -0.949)
			(end -0.778 -0.776)
			(stroke
				(width 0.15)
				(type solid)
			)
			(layer "B.SilkS")
		)
		(fp_line
			(start -0.724 0.778)
			(end -0.499 0.974)
			(stroke
				(width 0.15)
				(type solid)
			)
			(layer "B.SilkS")
		)
		(fp_line
			(start -0.424 -0.949)
			(end -0.778 -0.949)
			(stroke
				(width 0.15)
				(type solid)
			)
			(layer "B.SilkS")
		)
		(fp_line
			(start 0.526 -0.972)
			(end 0.776 -0.972)
			(stroke
				(width 0.15)
				(type solid)
			)
			(layer "B.SilkS")
		)
		(fp_line
			(start 0.526 0.974)
			(end 0.776 0.974)
			(stroke
				(width 0.15)
				(type solid)
			)
			(layer "B.SilkS")
		)
		(fp_line
			(start 0.776 -0.972)
			(end 0.776 -0.776)
			(stroke
				(width 0.15)
				(type solid)
			)
			(layer "B.SilkS")
		)
		(fp_line
			(start 0.776 0.778)
			(end 0.776 0.974)
			(stroke
				(width 0.15)
				(type solid)
			)
			(layer "B.SilkS")
		)
		(fp_circle
			(center -0.903 0.999)
			(end -0.952 0.95)
			(stroke
				(width 0.15)
				(type solid)
			)
			(fill yes)
			(layer "B.SilkS")
		)
		(fp_rect
			(start 1.19 1.12)
			(end -1.2 -1.1)
			(stroke
				(width 0.05)
				(type solid)
			)
			(fill no)
			(layer "B.CrtYd")
		)
		(fp_line
			(start -0.653 -0.847)
			(end -0.653 0.678)
			(stroke
				(width 0.15)
				(type solid)
			)
			(layer "B.Fab")
		)
		(fp_line
			(start -0.653 -0.847)
			(end 0.651 -0.847)
			(stroke
				(width 0.15)
				(type solid)
			)
			(layer "B.Fab")
		)
		(fp_line
			(start -0.653 0.678)
			(end -0.453 0.849)
			(stroke
				(width 0.15)
				(type solid)
			)
			(layer "B.Fab")
		)
		(fp_line
			(start 0.651 -0.847)
			(end 0.651 0.849)
			(stroke
				(width 0.15)
				(type solid)
			)
			(layer "B.Fab")
		)
		(fp_line
			(start 0.651 0.849)
			(end -0.453 0.849)
			(stroke
				(width 0.15)
				(type solid)
			)
			(layer "B.Fab")
		)
		(pad "1" smd roundrect
			(at -0.749 0.499 90)
			(size 0.3 0.6)
			(layers "B.Cu" "B.Mask" "B.Paste")
			(roundrect_rratio 0.25)
			(net 5 "+12V")
			(pinfunction "V_{IN}")
			(pintype "power_in")
		)
		(pad "2" smd roundrect
			(at -0.749 -0.001 90)
			(size 0.3 0.6)
			(layers "B.Cu" "B.Mask" "B.Paste")
			(roundrect_rratio 0.25)
			(net 23 "Net-(U4-SW)")
			(pinfunction "SW")
			(pintype "power_out")
		)
		(pad "3" smd roundrect
			(at -0.749 -0.497 90)
			(size 0.3 0.6)
			(layers "B.Cu" "B.Mask" "B.Paste")
			(roundrect_rratio 0.25)
			(net 2 "GND")
			(pinfunction "GND")
			(pintype "power_in")
		)
		(pad "4" smd roundrect
			(at 0.747 -0.497 90)
			(size 0.3 0.6)
			(layers "B.Cu" "B.Mask" "B.Paste")
			(roundrect_rratio 0.25)
			(net 24 "Net-(U4-BST)")
			(pinfunction "BST")
			(pintype "output")
		)
		(pad "5" smd roundrect
			(at 0.747 -0.001 90)
			(size 0.3 0.6)
			(layers "B.Cu" "B.Mask" "B.Paste")
			(roundrect_rratio 0.25)
			(net 9 "Net-(U4-EN)")
			(pinfunction "EN")
			(pintype "input")
		)
		(pad "6" smd roundrect
			(at 0.747 0.499 90)
			(size 0.3 0.6)
			(layers "B.Cu" "B.Mask" "B.Paste")
			(roundrect_rratio 0.25)
			(net 39 "Net-(U4-FB)")
			(pinfunction "FB")
			(pintype "input")
		)
	)
)
